(kicad_pcb
	(version 20260206)
	(generator "pcbnew")
	(generator_version "10.0")
	(general
		(thickness 1.6)
		(legacy_teardrops no)
	)
	(paper "A4")
	(title_block
		(title "04192023_DAF0TMB3IC0_F0TG_MB_C_brd_V02_OCP.brd")
		(comment 1 "Grand Teton / footprints 1677-1683 of 8354")
	)
	(layers
		(0 "F.Cu" signal "TOP")
		(4 "In1.Cu" signal "GND")
		(6 "In2.Cu" signal "IN1")
		(8 "In3.Cu" signal "GND1")
		(10 "In4.Cu" signal "IN2")
		(12 "In5.Cu" signal "GND2")
		(14 "In6.Cu" signal "IN3")
		(16 "In7.Cu" signal "GND3")
		(18 "In8.Cu" signal "VCC")
		(20 "In9.Cu" signal "VCC1")
		(22 "In10.Cu" signal "GND4")
		(24 "In11.Cu" signal "IN4")
		(26 "In12.Cu" signal "GND5")
		(28 "In13.Cu" signal "IN5")
		(30 "In14.Cu" signal "GND6")
		(32 "In15.Cu" signal "IN6")
		(34 "In16.Cu" signal "GND7")
		(2 "B.Cu" signal "BOTTOM")
		(9 "F.Adhes" user "F.Adhesive")
		(11 "B.Adhes" user "B.Adhesive")
		(13 "F.Paste" user "Package Geometry/Pastemask Top")
		(15 "B.Paste" user "Package Geometry/Pastemask Bottom")
		(5 "F.SilkS" user "Ref Des/Silkscreen Top")
		(7 "B.SilkS" user "Ref Des/Silkscreen Bottom")
		(1 "F.Mask" user "Board Geometry/Soldermask Top")
		(3 "B.Mask" user "Board Geometry/Soldermask Bottom")
		(17 "Dwgs.User" user "User.Drawings")
		(19 "Cmts.User" user "User.Comments")
		(21 "Eco1.User" user "User.Eco1")
		(23 "Eco2.User" user "User.Eco2")
		(25 "Edge.Cuts" user "Board Geometry/Outline")
		(27 "Margin" user)
		(31 "F.CrtYd" user "Package Geometry/Place Bound Top")
		(29 "B.CrtYd" user "Package Geometry/Place Bound Bottom")
		(35 "F.Fab" user "Ref Des/Assembly Top")
		(33 "B.Fab" user "Ref Des/Assembly Bottom")
	)
	(footprint ""
		(layer "F.Cu")
		(at 30.315662 -429.759364 90)
		(property "Reference" "R3281"
			(at 0 0 90)
			(layer "F.SilkS")
			(hide yes)
			(effects
				(font
					(size 1.27 1.27)
				)
			)
		)
		(property "Value" ""
			(at 0 0 90)
			(layer "F.Fab")
			(effects
				(font
					(size 1.27 1.27)
				)
			)
		)
		(duplicate_pad_numbers_are_jumpers no)
		(fp_line
			(start 0.7874 -0.4064)
			(end 0.7874 0.4064)
			(stroke
				(width 0.1524)
				(type default)
			)
			(layer "F.SilkS")
		)
		(fp_line
			(start -0.7874 -0.4064)
			(end 0.7874 -0.4064)
			(stroke
				(width 0.1524)
				(type default)
			)
			(layer "F.SilkS")
		)
		(fp_line
			(start 0.7874 0.4064)
			(end -0.7874 0.4064)
			(stroke
				(width 0.1524)
				(type default)
			)
			(layer "F.SilkS")
		)
		(fp_line
			(start -0.7874 0.4064)
			(end -0.7874 -0.4064)
			(stroke
				(width 0.1524)
				(type default)
			)
			(layer "F.SilkS")
		)
		(fp_line
			(start -0.12065 -0.305054)
			(end -0.12065 -0.2794)
			(stroke
				(width 0.1)
				(type default)
			)
			(layer "F.Fab")
		)
		(fp_line
			(start -0.67945 -0.305054)
			(end -0.12065 -0.305054)
			(stroke
				(width 0.1)
				(type default)
			)
			(layer "F.Fab")
		)
		(fp_line
			(start 0.67945 -0.3048)
			(end 0.67945 0.3048)
			(stroke
				(width 0.1)
				(type default)
			)
			(layer "F.Fab")
		)
		(fp_line
			(start 0.12065 -0.3048)
			(end 0.67945 -0.3048)
			(stroke
				(width 0.1)
				(type default)
			)
			(layer "F.Fab")
		)
		(fp_line
			(start 0.12065 -0.2794)
			(end 0.12065 -0.3048)
			(stroke
				(width 0.1)
				(type default)
			)
			(layer "F.Fab")
		)
		(fp_line
			(start -0.12065 -0.2794)
			(end 0.12065 -0.2794)
			(stroke
				(width 0.1)
				(type default)
			)
			(layer "F.Fab")
		)
		(fp_line
			(start 0.120396 0.2794)
			(end -0.12065 0.2794)
			(stroke
				(width 0.1)
				(type default)
			)
			(layer "F.Fab")
		)
		(fp_line
			(start -0.12065 0.2794)
			(end -0.12065 0.3048)
			(stroke
				(width 0.1)
				(type default)
			)
			(layer "F.Fab")
		)
		(fp_line
			(start 0.67945 0.3048)
			(end 0.120396 0.3048)
			(stroke
				(width 0.1)
				(type default)
			)
			(layer "F.Fab")
		)
		(fp_line
			(start 0.120396 0.3048)
			(end 0.120396 0.2794)
			(stroke
				(width 0.1)
				(type default)
			)
			(layer "F.Fab")
		)
		(fp_line
			(start -0.12065 0.3048)
			(end -0.67945 0.3048)
			(stroke
				(width 0.1)
				(type default)
			)
			(layer "F.Fab")
		)
		(fp_line
			(start -0.67945 0.3048)
			(end -0.67945 -0.305054)
			(stroke
				(width 0.1)
				(type default)
			)
			(layer "F.Fab")
		)
		(pad "1" smd circle
			(at -0.40005 0 90)
			(size 0 0)
			(layers "F.Cu" "F.Mask" "F.Paste")
			(net "FM_P2E_EQB1")
		)
		(pad "2" smd circle
			(at 0.40005 0 90)
			(size 0 0)
			(layers "F.Cu" "F.Mask" "F.Paste")
			(net "GND")
		)
	)
	(footprint ""
		(layer "F.Cu")
		(at 167.79621 -395.6304 -90)
		(property "Reference" "R854"
			(at 0 0 270)
			(layer "F.SilkS")
			(hide yes)
			(effects
				(font
					(size 1.27 1.27)
				)
			)
		)
		(property "Value" ""
			(at 0 0 270)
			(layer "F.Fab")
			(effects
				(font
					(size 1.27 1.27)
				)
			)
		)
		(duplicate_pad_numbers_are_jumpers no)
		(fp_line
			(start -0.32512 0.175006)
			(end -0.32512 -0.175006)
			(stroke
				(width 0.1)
				(type default)
			)
			(layer "F.Fab")
		)
		(fp_line
			(start 0.32512 0.175006)
			(end -0.32512 0.175006)
			(stroke
				(width 0.1)
				(type default)
			)
			(layer "F.Fab")
		)
		(fp_line
			(start -0.32512 -0.175006)
			(end 0.32512 -0.175006)
			(stroke
				(width 0.1)
				(type default)
			)
			(layer "F.Fab")
		)
		(fp_line
			(start 0.32512 -0.175006)
			(end 0.32512 0.175006)
			(stroke
				(width 0.1)
				(type default)
			)
			(layer "F.Fab")
		)
		(pad "1" smd rect
			(at -0.2667 0 270)
			(size 0.3048 0.381)
			(layers "F.Cu" "F.Mask" "F.Paste")
			(net "RST_RT_CPU1_P2_PERST_N")
		)
		(pad "2" smd rect
			(at 0.2667 0 90)
			(size 0.3048 0.381)
			(layers "F.Cu" "F.Mask" "F.Paste")
			(net "RST_RT_CPU1_P2_PERST_R_N")
		)
	)
	(footprint ""
		(layer "F.Cu")
		(at 302.241458 -109.779308 180)
		(property "Reference" "R54"
			(at 0 0 180)
			(layer "F.SilkS")
			(hide yes)
			(effects
				(font
					(size 1.27 1.27)
				)
			)
		)
		(property "Value" ""
			(at 0 0 180)
			(layer "F.Fab")
			(effects
				(font
					(size 1.27 1.27)
				)
			)
		)
		(duplicate_pad_numbers_are_jumpers no)
		(fp_line
			(start 0.7874 0.4064)
			(end -0.7874 0.4064)
			(stroke
				(width 0.1524)
				(type default)
			)
			(layer "F.SilkS")
		)
		(fp_line
			(start 0.7874 -0.4064)
			(end 0.7874 0.4064)
			(stroke
				(width 0.1524)
				(type default)
			)
			(layer "F.SilkS")
		)
		(fp_line
			(start -0.7874 0.4064)
			(end -0.7874 -0.4064)
			(stroke
				(width 0.1524)
				(type default)
			)
			(layer "F.SilkS")
		)
		(fp_line
			(start -0.7874 -0.4064)
			(end 0.7874 -0.4064)
			(stroke
				(width 0.1524)
				(type default)
			)
			(layer "F.SilkS")
		)
		(fp_line
			(start 0.67945 0.3048)
			(end 0.120396 0.3048)
			(stroke
				(width 0.1)
				(type default)
			)
			(layer "F.Fab")
		)
		(fp_line
			(start 0.67945 -0.3048)
			(end 0.67945 0.3048)
			(stroke
				(width 0.1)
				(type default)
			)
			(layer "F.Fab")
		)
		(fp_line
			(start 0.12065 -0.2794)
			(end 0.12065 -0.3048)
			(stroke
				(width 0.1)
				(type default)
			)
			(layer "F.Fab")
		)
		(fp_line
			(start 0.12065 -0.3048)
			(end 0.67945 -0.3048)
			(stroke
				(width 0.1)
				(type default)
			)
			(layer "F.Fab")
		)
		(fp_line
			(start 0.120396 0.3048)
			(end 0.120396 0.2794)
			(stroke
				(width 0.1)
				(type default)
			)
			(layer "F.Fab")
		)
		(fp_line
			(start 0.120396 0.2794)
			(end -0.12065 0.2794)
			(stroke
				(width 0.1)
				(type default)
			)
			(layer "F.Fab")
		)
		(fp_line
			(start -0.12065 0.3048)
			(end -0.67945 0.3048)
			(stroke
				(width 0.1)
				(type default)
			)
			(layer "F.Fab")
		)
		(fp_line
			(start -0.12065 0.2794)
			(end -0.12065 0.3048)
			(stroke
				(width 0.1)
				(type default)
			)
			(layer "F.Fab")
		)
		(fp_line
			(start -0.12065 -0.2794)
			(end 0.12065 -0.2794)
			(stroke
				(width 0.1)
				(type default)
			)
			(layer "F.Fab")
		)
		(fp_line
			(start -0.12065 -0.305054)
			(end -0.12065 -0.2794)
			(stroke
				(width 0.1)
				(type default)
			)
			(layer "F.Fab")
		)
		(fp_line
			(start -0.67945 0.3048)
			(end -0.67945 -0.305054)
			(stroke
				(width 0.1)
				(type default)
			)
			(layer "F.Fab")
		)
		(fp_line
			(start -0.67945 -0.305054)
			(end -0.12065 -0.305054)
			(stroke
				(width 0.1)
				(type default)
			)
			(layer "F.Fab")
		)
		(pad "1" smd circle
			(at -0.40005 0 180)
			(size 0 0)
			(layers "F.Cu" "F.Mask" "F.Paste")
			(net "CPU_FRU_ADDR2")
		)
		(pad "2" smd circle
			(at 0.40005 0 180)
			(size 0 0)
			(layers "F.Cu" "F.Mask" "F.Paste")
			(net "GND")
		)
	)
	(footprint ""
		(layer "F.Cu")
		(at 380.318772 -178.0921 -90)
		(property "Reference" "PR348"
			(at 0 0 270)
			(layer "F.SilkS")
			(hide yes)
			(effects
				(font
					(size 1.27 1.27)
				)
			)
		)
		(property "Value" ""
			(at 0 0 270)
			(layer "F.Fab")
			(effects
				(font
					(size 1.27 1.27)
				)
			)
		)
		(duplicate_pad_numbers_are_jumpers no)
		(fp_line
			(start -0.7874 0.4064)
			(end -0.7874 -0.4064)
			(stroke
				(width 0.1524)
				(type default)
			)
			(layer "F.SilkS")
		)
		(fp_line
			(start 0.7874 0.4064)
			(end -0.7874 0.4064)
			(stroke
				(width 0.1524)
				(type default)
			)
			(layer "F.SilkS")
		)
		(fp_line
			(start -0.7874 -0.4064)
			(end 0.7874 -0.4064)
			(stroke
				(width 0.1524)
				(type default)
			)
			(layer "F.SilkS")
		)
		(fp_line
			(start 0.7874 -0.4064)
			(end 0.7874 0.4064)
			(stroke
				(width 0.1524)
				(type default)
			)
			(layer "F.SilkS")
		)
		(fp_line
			(start -0.67945 0.3048)
			(end -0.67945 -0.305054)
			(stroke
				(width 0.1)
				(type default)
			)
			(layer "F.Fab")
		)
		(fp_line
			(start -0.12065 0.3048)
			(end -0.67945 0.3048)
			(stroke
				(width 0.1)
				(type default)
			)
			(layer "F.Fab")
		)
		(fp_line
			(start 0.120396 0.3048)
			(end 0.120396 0.2794)
			(stroke
				(width 0.1)
				(type default)
			)
			(layer "F.Fab")
		)
		(fp_line
			(start 0.67945 0.3048)
			(end 0.120396 0.3048)
			(stroke
				(width 0.1)
				(type default)
			)
			(layer "F.Fab")
		)
		(fp_line
			(start -0.12065 0.2794)
			(end -0.12065 0.3048)
			(stroke
				(width 0.1)
				(type default)
			)
			(layer "F.Fab")
		)
		(fp_line
			(start 0.120396 0.2794)
			(end -0.12065 0.2794)
			(stroke
				(width 0.1)
				(type default)
			)
			(layer "F.Fab")
		)
		(fp_line
			(start -0.12065 -0.2794)
			(end 0.12065 -0.2794)
			(stroke
				(width 0.1)
				(type default)
			)
			(layer "F.Fab")
		)
		(fp_line
			(start 0.12065 -0.2794)
			(end 0.12065 -0.3048)
			(stroke
				(width 0.1)
				(type default)
			)
			(layer "F.Fab")
		)
		(fp_line
			(start 0.12065 -0.3048)
			(end 0.67945 -0.3048)
			(stroke
				(width 0.1)
				(type default)
			)
			(layer "F.Fab")
		)
		(fp_line
			(start 0.67945 -0.3048)
			(end 0.67945 0.3048)
			(stroke
				(width 0.1)
				(type default)
			)
			(layer "F.Fab")
		)
		(fp_line
			(start -0.67945 -0.305054)
			(end -0.12065 -0.305054)
			(stroke
				(width 0.1)
				(type default)
			)
			(layer "F.Fab")
		)
		(fp_line
			(start -0.12065 -0.305054)
			(end -0.12065 -0.2794)
			(stroke
				(width 0.1)
				(type default)
			)
			(layer "F.Fab")
		)
		(pad "1" smd circle
			(at -0.40005 0 270)
			(size 0 0)
			(layers "F.Cu" "F.Mask" "F.Paste")
			(net "SW_PVDDCR_CPU0_P0_BOOT3")
		)
		(pad "2" smd circle
			(at 0.40005 0 270)
			(size 0 0)
			(layers "F.Cu" "F.Mask" "F.Paste")
			(net "SW_PVDDCR_CPU0_P0_BOOT3_RC")
		)
	)
	(footprint ""
		(layer "F.Cu")
		(at 103.145844 -394.68806 90)
		(property "Reference" "R6706"
			(at 0 0 90)
			(layer "F.SilkS")
			(hide yes)
			(effects
				(font
					(size 1.27 1.27)
				)
			)
		)
		(property "Value" ""
			(at 0 0 90)
			(layer "F.Fab")
			(effects
				(font
					(size 1.27 1.27)
				)
			)
		)
		(duplicate_pad_numbers_are_jumpers no)
		(fp_line
			(start 0.32512 -0.175006)
			(end 0.32512 0.175006)
			(stroke
				(width 0.1)
				(type default)
			)
			(layer "F.Fab")
		)
		(fp_line
			(start -0.32512 -0.175006)
			(end 0.32512 -0.175006)
			(stroke
				(width 0.1)
				(type default)
			)
			(layer "F.Fab")
		)
		(fp_line
			(start 0.32512 0.175006)
			(end -0.32512 0.175006)
			(stroke
				(width 0.1)
				(type default)
			)
			(layer "F.Fab")
		)
		(fp_line
			(start -0.32512 0.175006)
			(end -0.32512 -0.175006)
			(stroke
				(width 0.1)
				(type default)
			)
			(layer "F.Fab")
		)
		(pad "1" smd rect
			(at -0.2667 0 90)
			(size 0.3048 0.381)
			(layers "F.Cu" "F.Mask" "F.Paste")
			(net "P1V8_CPU1_RT_1D")
		)
		(pad "2" smd rect
			(at 0.2667 0 270)
			(size 0.3048 0.381)
			(layers "F.Cu" "F.Mask" "F.Paste")
			(net "SMB_RT_CPU1_P0_ROM_R_SCL")
		)
	)
	(footprint ""
		(layer "F.Cu")
		(at 104.469946 -52.86248 90)
		(property "Reference" "R6318"
			(at 0 0 90)
			(layer "F.SilkS")
			(hide yes)
			(effects
				(font
					(size 1.27 1.27)
				)
			)
		)
		(property "Value" ""
			(at 0 0 90)
			(layer "F.Fab")
			(effects
				(font
					(size 1.27 1.27)
				)
			)
		)
		(duplicate_pad_numbers_are_jumpers no)
		(fp_line
			(start 0.7874 -0.4064)
			(end 0.7874 0.4064)
			(stroke
				(width 0.1524)
				(type default)
			)
			(layer "F.SilkS")
		)
		(fp_line
			(start -0.7874 -0.4064)
			(end 0.7874 -0.4064)
			(stroke
				(width 0.1524)
				(type default)
			)
			(layer "F.SilkS")
		)
		(fp_line
			(start 0.7874 0.4064)
			(end -0.7874 0.4064)
			(stroke
				(width 0.1524)
				(type default)
			)
			(layer "F.SilkS")
		)
		(fp_line
			(start -0.7874 0.4064)
			(end -0.7874 -0.4064)
			(stroke
				(width 0.1524)
				(type default)
			)
			(layer "F.SilkS")
		)
		(fp_line
			(start -0.12065 -0.305054)
			(end -0.12065 -0.2794)
			(stroke
				(width 0.1)
				(type default)
			)
			(layer "F.Fab")
		)
		(fp_line
			(start -0.67945 -0.305054)
			(end -0.12065 -0.305054)
			(stroke
				(width 0.1)
				(type default)
			)
			(layer "F.Fab")
		)
		(fp_line
			(start 0.67945 -0.3048)
			(end 0.67945 0.3048)
			(stroke
				(width 0.1)
				(type default)
			)
			(layer "F.Fab")
		)
		(fp_line
			(start 0.12065 -0.3048)
			(end 0.67945 -0.3048)
			(stroke
				(width 0.1)
				(type default)
			)
			(layer "F.Fab")
		)
		(fp_line
			(start 0.12065 -0.2794)
			(end 0.12065 -0.3048)
			(stroke
				(width 0.1)
				(type default)
			)
			(layer "F.Fab")
		)
		(fp_line
			(start -0.12065 -0.2794)
			(end 0.12065 -0.2794)
			(stroke
				(width 0.1)
				(type default)
			)
			(layer "F.Fab")
		)
		(fp_line
			(start 0.120396 0.2794)
			(end -0.12065 0.2794)
			(stroke
				(width 0.1)
				(type default)
			)
			(layer "F.Fab")
		)
		(fp_line
			(start -0.12065 0.2794)
			(end -0.12065 0.3048)
			(stroke
				(width 0.1)
				(type default)
			)
			(layer "F.Fab")
		)
		(fp_line
			(start 0.67945 0.3048)
			(end 0.120396 0.3048)
			(stroke
				(width 0.1)
				(type default)
			)
			(layer "F.Fab")
		)
		(fp_line
			(start 0.120396 0.3048)
			(end 0.120396 0.2794)
			(stroke
				(width 0.1)
				(type default)
			)
			(layer "F.Fab")
		)
		(fp_line
			(start -0.12065 0.3048)
			(end -0.67945 0.3048)
			(stroke
				(width 0.1)
				(type default)
			)
			(layer "F.Fab")
		)
		(fp_line
			(start -0.67945 0.3048)
			(end -0.67945 -0.305054)
			(stroke
				(width 0.1)
				(type default)
			)
			(layer "F.Fab")
		)
		(pad "1" smd circle
			(at -0.40005 0 90)
			(size 0 0)
			(layers "F.Cu" "F.Mask" "F.Paste")
			(net "P5V_AUX")
		)
		(pad "2" smd circle
			(at 0.40005 0 90)
			(size 0 0)
			(layers "F.Cu" "F.Mask" "F.Paste")
			(net "USB_HUB2_TI_USB_VBUS")
		)
	)
	(footprint ""
		(layer "F.Cu")
		(at 223.266 -82.804 180)
		(property "Reference" "R8099"
			(at 0 0 180)
			(layer "F.SilkS")
			(hide yes)
			(effects
				(font
					(size 1.27 1.27)
				)
			)
		)
		(property "Value" ""
			(at 0 0 180)
			(layer "F.Fab")
			(effects
				(font
					(size 1.27 1.27)
				)
			)
		)
		(duplicate_pad_numbers_are_jumpers no)
		(fp_line
			(start 0.7874 0.4064)
			(end -0.7874 0.4064)
			(stroke
				(width 0.1524)
				(type default)
			)
			(layer "F.SilkS")
		)
		(fp_line
			(start 0.7874 -0.4064)
			(end 0.7874 0.4064)
			(stroke
				(width 0.1524)
				(type default)
			)
			(layer "F.SilkS")
		)
		(fp_line
			(start -0.7874 0.4064)
			(end -0.7874 -0.4064)
			(stroke
				(width 0.1524)
				(type default)
			)
			(layer "F.SilkS")
		)
		(fp_line
			(start -0.7874 -0.4064)
			(end 0.7874 -0.4064)
			(stroke
				(width 0.1524)
				(type default)
			)
			(layer "F.SilkS")
		)
		(fp_line
			(start 0.67945 0.3048)
			(end 0.120396 0.3048)
			(stroke
				(width 0.1)
				(type default)
			)
			(layer "F.Fab")
		)
		(fp_line
			(start 0.67945 -0.3048)
			(end 0.67945 0.3048)
			(stroke
				(width 0.1)
				(type default)
			)
			(layer "F.Fab")
		)
		(fp_line
			(start 0.12065 -0.2794)
			(end 0.12065 -0.3048)
			(stroke
				(width 0.1)
				(type default)
			)
			(layer "F.Fab")
		)
		(fp_line
			(start 0.12065 -0.3048)
			(end 0.67945 -0.3048)
			(stroke
				(width 0.1)
				(type default)
			)
			(layer "F.Fab")
		)
		(fp_line
			(start 0.120396 0.3048)
			(end 0.120396 0.2794)
			(stroke
				(width 0.1)
				(type default)
			)
			(layer "F.Fab")
		)
		(fp_line
			(start 0.120396 0.2794)
			(end -0.12065 0.2794)
			(stroke
				(width 0.1)
				(type default)
			)
			(layer "F.Fab")
		)
		(fp_line
			(start -0.12065 0.3048)
			(end -0.67945 0.3048)
			(stroke
				(width 0.1)
				(type default)
			)
			(layer "F.Fab")
		)
		(fp_line
			(start -0.12065 0.2794)
			(end -0.12065 0.3048)
			(stroke
				(width 0.1)
				(type default)
			)
			(layer "F.Fab")
		)
		(fp_line
			(start -0.12065 -0.2794)
			(end 0.12065 -0.2794)
			(stroke
				(width 0.1)
				(type default)
			)
			(layer "F.Fab")
		)
		(fp_line
			(start -0.12065 -0.305054)
			(end -0.12065 -0.2794)
			(stroke
				(width 0.1)
				(type default)
			)
			(layer "F.Fab")
		)
		(fp_line
			(start -0.67945 0.3048)
			(end -0.67945 -0.305054)
			(stroke
				(width 0.1)
				(type default)
			)
			(layer "F.Fab")
		)
		(fp_line
			(start -0.67945 -0.305054)
			(end -0.12065 -0.305054)
			(stroke
				(width 0.1)
				(type default)
			)
			(layer "F.Fab")
		)
		(pad "1" smd circle
			(at -0.40005 0 180)
			(size 0 0)
			(layers "F.Cu" "F.Mask" "F.Paste")
			(net "P3V3_E1S_PWRGD_0_R1")
		)
		(pad "2" smd circle
			(at 0.40005 0 180)
			(size 0 0)
			(layers "F.Cu" "F.Mask" "F.Paste")
			(net "GND")
		)
	)
)
